# TIMECARD (Time Appliance Project (Time Card)) — schematic netlist excerpt (pin names and nets, part order shuffled) for the footprints in the layout excerpt that follows; sources: Cadence DE-HDL packaged netlist, KiCad conversion of R4006-B0001-02_R01.brd

R104  RESISTOR  4.7KOHM 1%  pkg SMC_0402R_H016  page 21 : \1\ = UNNAMED_527_RESISTOR_I126_1 ; \2\ = SG
R485  RESISTOR  33OHM 1%  pkg SMC_0402R_H016  page 24 : \1\ = FPGA_OUT_MUX3_SEL ; \2\ = MUX3_SEL

(kicad_pcb
	(version 20260206)
	(generator "pcbnew")
	(generator_version "10.0")
	(general
		(thickness 1.6)
		(legacy_teardrops no)
	)
	(paper "A4")
	(title_block
		(title "timecard-production-celestica-r4006 — R4006-B0001-02_R01.brd")
		(comment 1 "Time Appliance Project (Time Card) / footprints 421-422 of 1113")
	)
	(layers
		(0 "F.Cu" signal "TOP")
		(4 "In1.Cu" signal "L02_GND1")
		(6 "In2.Cu" signal "L03_SIG1")
		(8 "In3.Cu" signal "L04_GND2")
		(10 "In4.Cu" signal "L05_VCC1")
		(12 "In5.Cu" signal "L06_VCC2")
		(14 "In6.Cu" signal "L07_GND3")
		(16 "In7.Cu" signal "L08_SIG2")
		(18 "In8.Cu" signal "L09_GND4")
		(2 "B.Cu" signal "BOTTOM")
		(9 "F.Adhes" user "F.Adhesive")
		(11 "B.Adhes" user "B.Adhesive")
		(13 "F.Paste" user "Package Geometry/Pastemask Top")
		(15 "B.Paste" user "Package Geometry/Pastemask Bottom")
		(5 "F.SilkS" user "Ref Des/Silkscreen Top")
		(7 "B.SilkS" user "Ref Des/Silkscreen Bottom")
		(1 "F.Mask" user "Board Geometry/Soldermask Top")
		(3 "B.Mask" user "Board Geometry/Soldermask Bottom")
		(17 "Dwgs.User" user "User.Drawings")
		(19 "Cmts.User" user "User.Comments")
		(21 "Eco1.User" user "User.Eco1")
		(23 "Eco2.User" user "User.Eco2")
		(25 "Edge.Cuts" user "Board Geometry/Outline")
		(27 "Margin" user)
		(31 "F.CrtYd" user "Package Geometry/Place Bound Top")
		(29 "B.CrtYd" user "Package Geometry/Place Bound Bottom")
		(35 "F.Fab" user "Ref Des/Assembly Top")
		(33 "B.Fab" user "Ref Des/Assembly Bottom")
	)
	(footprint ""
		(layer "F.Cu")
		(at 91.5416 -44.868846 -90)
		(property "Reference" "R104"
			(at -0.597154 -1.44907 90)
			(unlocked yes)
			(layer "F.SilkS")
			(effects
				(font
					(size 0.7874 0.5842)
					(thickness 0.1524)
				)
			)
		)
		(property "Value" "VAL*"
			(at 0.02032 2.13233 270)
			(unlocked yes)
			(layer "F.Fab")
			(hide yes)
			(effects
				(font
					(size 0.7874 0.5842)
					(thickness 0.1524)
				)
			)
		)
		(property "Device Type" "RESISTOR-G155-14701-01,4.7KOHMA"
			(at 0.008382 1.210564 270)
			(unlocked yes)
			(layer "F.Fab")
			(hide yes)
			(effects
				(font
					(size 0.7874 0.5842)
					(thickness 0.1524)
				)
			)
		)
		(property "User Part Number" "PARTNUM*"
			(at 0.02032 4.024884 270)
			(unlocked yes)
			(layer "Cmts.User")
			(hide yes)
			(effects
				(font
					(size 0.7874 0.5842)
					(thickness 0.1524)
				)
			)
		)
		(property "Tolerance" "TOL*"
			(at 0.044704 3.05435 270)
			(unlocked yes)
			(layer "Cmts.User")
			(hide yes)
			(effects
				(font
					(size 0.7874 0.5842)
					(thickness 0.1524)
				)
			)
		)
		(duplicate_pad_numbers_are_jumpers no)
		(fp_line
			(start -1.143 0.5588)
			(end 1.143 0.5588)
			(stroke
				(width 0.1)
				(type default)
			)
			(layer "F.SilkS")
		)
		(fp_line
			(start 1.143 0.5588)
			(end 1.143 -0.5588)
			(stroke
				(width 0.1)
				(type default)
			)
			(layer "F.SilkS")
		)
		(fp_line
			(start -1.143 -0.5588)
			(end -1.143 0.5588)
			(stroke
				(width 0.1)
				(type default)
			)
			(layer "F.SilkS")
		)
		(fp_line
			(start 1.143 -0.5588)
			(end -1.143 -0.5588)
			(stroke
				(width 0.1)
				(type default)
			)
			(layer "F.SilkS")
		)
		(fp_rect
			(start -1.143 -0.5588)
			(end 1.143 0.5588)
			(stroke
				(width 0)
				(type default)
			)
			(fill no)
			(layer "F.CrtYd")
		)
		(fp_line
			(start -0.508 0.3048)
			(end 0.508 0.3048)
			(stroke
				(width 0.1)
				(type default)
			)
			(layer "F.Fab")
		)
		(fp_line
			(start 0.508 0.3048)
			(end 0.508 -0.3048)
			(stroke
				(width 0.1)
				(type default)
			)
			(layer "F.Fab")
		)
		(fp_line
			(start -0.508 -0.3048)
			(end -0.508 0.3048)
			(stroke
				(width 0.1)
				(type default)
			)
			(layer "F.Fab")
		)
		(fp_line
			(start 0.508 -0.3048)
			(end -0.508 -0.3048)
			(stroke
				(width 0.1)
				(type default)
			)
			(layer "F.Fab")
		)
		(pad "1" smd rect
			(at -0.5334 0 270)
			(size 0.7112 0.6096)
			(layers "F.Cu" "F.Mask" "F.Paste")
			(net "UNNAMED_527_RESISTOR_I126_1")
		)
		(pad "2" smd rect
			(at 0.5334 0 270)
			(size 0.7112 0.6096)
			(layers "F.Cu" "F.Mask" "F.Paste")
			(net "SG")
		)
		(zone
			(layer "F.Cu")
			(hatch none 0.5)
			(connect_pads
				(clearance 0)
			)
			(min_thickness 0.25)
			(keepout
				(tracks allowed)
				(vias not_allowed)
				(pads allowed)
				(copperpour not_allowed)
				(footprints allowed)
			)
			(placement
				(enabled no)
				(sheetname "")
			)
			(fill
				(thermal_gap 0.5)
				(thermal_bridge_width 0.5)
				(island_removal_mode 0)
			)
			(polygon
				(pts
					(xy 91.8464 -44.945046) (xy 91.2368 -44.945046) (xy 91.2368 -44.792646) (xy 91.8464 -44.792646)
				)
			)
		)
	)
	(footprint ""
		(layer "F.Cu")
		(at 119.761 -24.511)
		(property "Reference" "R485"
			(at -2.794 -0.08763 0)
			(unlocked yes)
			(layer "F.SilkS")
			(effects
				(font
					(size 0.7874 0.5842)
					(thickness 0.1524)
				)
			)
		)
		(property "Value" "VAL*"
			(at 0.02032 2.13233 0)
			(unlocked yes)
			(layer "F.Fab")
			(hide yes)
			(effects
				(font
					(size 0.7874 0.5842)
					(thickness 0.1524)
				)
			)
		)
		(property "Tolerance" "TOL*"
			(at 0.044704 3.05435 0)
			(unlocked yes)
			(layer "Cmts.User")
			(hide yes)
			(effects
				(font
					(size 0.7874 0.5842)
					(thickness 0.1524)
				)
			)
		)
		(property "User Part Number" "PARTNUM*"
			(at 0.02032 4.024884 0)
			(unlocked yes)
			(layer "Cmts.User")
			(hide yes)
			(effects
				(font
					(size 0.7874 0.5842)
					(thickness 0.1524)
				)
			)
		)
		(property "Device Type" "RESISTOR-G155-133R0-01,33OHM,1%"
			(at 0.008382 1.210564 0)
			(unlocked yes)
			(layer "F.Fab")
			(hide yes)
			(effects
				(font
					(size 0.7874 0.5842)
					(thickness 0.1524)
				)
			)
		)
		(duplicate_pad_numbers_are_jumpers no)
		(fp_line
			(start -1.143 -0.5588)
			(end -1.143 0.5588)
			(stroke
				(width 0.1)
				(type default)
			)
			(layer "F.SilkS")
		)
		(fp_line
			(start -1.143 0.5588)
			(end 1.143 0.5588)
			(stroke
				(width 0.1)
				(type default)
			)
			(layer "F.SilkS")
		)
		(fp_line
			(start 1.143 -0.5588)
			(end -1.143 -0.5588)
			(stroke
				(width 0.1)
				(type default)
			)
			(layer "F.SilkS")
		)
		(fp_line
			(start 1.143 0.5588)
			(end 1.143 -0.5588)
			(stroke
				(width 0.1)
				(type default)
			)
			(layer "F.SilkS")
		)
		(fp_poly
			(pts
				(xy -1.143 0.5588) (xy 1.143 0.5588) (xy 1.143 -0.5588) (xy -1.143 -0.5588)
			)
			(stroke
				(width 0)
				(type default)
			)
			(fill no)
			(layer "F.CrtYd")
		)
		(fp_line
			(start -0.508 -0.3048)
			(end -0.508 0.3048)
			(stroke
				(width 0.1)
				(type default)
			)
			(layer "F.Fab")
		)
		(fp_line
			(start -0.508 0.3048)
			(end 0.508 0.3048)
			(stroke
				(width 0.1)
				(type default)
			)
			(layer "F.Fab")
		)
		(fp_line
			(start 0.508 -0.3048)
			(end -0.508 -0.3048)
			(stroke
				(width 0.1)
				(type default)
			)
			(layer "F.Fab")
		)
		(fp_line
			(start 0.508 0.3048)
			(end 0.508 -0.3048)
			(stroke
				(width 0.1)
				(type default)
			)
			(layer "F.Fab")
		)
		(pad "1" smd rect
			(at -0.5334 0)
			(size 0.7112 0.6096)
			(layers "F.Cu" "F.Mask" "F.Paste")
			(net "FPGA_OUT_MUX3_SEL")
		)
		(pad "2" smd rect
			(at 0.5334 0)
			(size 0.7112 0.6096)
			(layers "F.Cu" "F.Mask" "F.Paste")
			(net "MUX3_SEL")
		)
		(zone
			(layer "F.Cu")
			(hatch none 0.5)
			(connect_pads
				(clearance 0)
			)
			(min_thickness 0.25)
			(keepout
				(tracks not_allowed)
				(vias allowed)
				(pads allowed)
				(copperpour not_allowed)
				(footprints allowed)
			)
			(placement
				(enabled no)
				(sheetname "")
			)
			(fill
				(thermal_gap 0.5)
				(thermal_bridge_width 0.5)
				(island_removal_mode 0)
			)
			(polygon
				(pts
					(xy 119.6848 -24.2062) (xy 119.8372 -24.2062) (xy 119.8372 -24.8158) (xy 119.6848 -24.8158)
				)
			)
		)
		(zone
			(layer "F.Cu")
			(hatch none 0.5)
			(connect_pads
				(clearance 0)
			)
			(min_thickness 0.25)
			(keepout
				(tracks allowed)
				(vias not_allowed)
				(pads allowed)
				(copperpour not_allowed)
				(footprints allowed)
			)
			(placement
				(enabled no)
				(sheetname "")
			)
			(fill
				(thermal_gap 0.5)
				(thermal_bridge_width 0.5)
				(island_removal_mode 0)
			)
			(polygon
				(pts
					(xy 119.6848 -24.2062) (xy 119.8372 -24.2062) (xy 119.8372 -24.8158) (xy 119.6848 -24.8158)
				)
			)
		)
	)
)
